# S9S_MB_2U (Grand Teton) — schematic netlist excerpt (pin names and nets, part order shuffled) for the footprints in the layout excerpt that follows; sources: Cadence DE-HDL packaged netlist, KiCad conversion of 03242023_DA0F0TMBIJ0_F0T_Motherboard_J_brd_V01_OCP.brd

U13  9SQ440NQQI8  IC  pkg QFN100_TH_0-5_8X8  page 208
  \25mpg\  = FM_CK440Q_DEV_25M_EN
  \25m1#\  = CLK_25M_CK440_CPU1_DN
  \25m1\  = CLK_25M_CK440_CPU1_DP
  \25m0#\  = CLK_25M_CK440_CPU0_DN
  \25m0\  = CLK_25M_CK440_CPU0_DP
  PFT_OUT  = TP_CLK_CK440_PFT_OUT_DP
  \pft_out#\  = TP_CLK_CK440_PFT_OUT_DN
  PFT_IN  = TP_CLK_PFT_IN_DP
  \pft_in#\  = TP_CLK_PFT_IN_DN
  SCLK  = SMB_HOST_CLK_3V3AUX_SCL
  SMB_ADR0_TRI  = CLK_CK440_SMB_ADDR0
  VDDXTAL  = P3V3_AUX_CLK_GEN_VDDXTAL_CK440
  XIN_CLKIN  = XTAL_CLK_GEN1_25M_X1
  GNDXTAL  = GND
  NC_A15  = NC_CK440_A15
  SS_EN_TRI  = FM_CLK_CK440_SS_EN
  \pwrgd||pwrdn#\  = FM_PLD_CLKS_DEV_EN
  \100m6#\  = NC_CLK_CK440_100M6_DN
  \100m6\  = NC_CLK_CK440_100M6_DP
  \100m5#\  = NC_CLK_CK440_100M5_DN
  \100m5\  = NC_CLK_CK440_100M5_DP
  \100m4#\  = NC_CLK_CK440_100M4_DN
  \100m4\  = NC_CLK_CK440_100M4_DP
  \100m3#\  = NC_CLK_CK440_100M3_DN
  \100m3\  = NC_CLK_CK440_100M3_DP
  \oe3#\  = CK440Q_OE_3
  \100m2#\  = NC_CLK_CK440_100M2_DN
  \100m2\  = NC_CLK_CK440_100M2_DP
  \oe2#\  = CK440Q_OE_2
  \oe1#\  = CK440Q_OE_1
  \100m1#\  = NC_CLK_CK440_100M1_DN
  \100m1\  = NC_CLK_CK440_100M1_DP
  \100m0#\  = CLK_100M_DB2000_DN
  \100m0\  = CLK_100M_DB2000_DP
  \mxck8#\  = NC_CLK_CK440_MXCK8_DN
  MXCK8  = NC_CLK_CK440_MXCK8_DP
  \mxck7#\  = NC_CLK_CK440_MXCK7_DN
  MXCK7  = NC_CLK_CK440_MXCK7_DP
  \mxck6#\  = NC_CLK_CK440_MXCK6_DN
  MXCK6  = NC_CLK_CK440_MXCK6_DP
  \mxck5#\  = NC_CLK_CK440_MXCK5_DN
  MXCK5  = NC_CLK_CK440_MXCK5_DP
  \mxck4#\  = NC_CLK_CK440_MXCK4_DN
  MXCK4  = NC_CLK_CK440_MXCK4_DP
  \mxck3#\  = NC_CLK_CK440_MXCK3_DN
  MXCK3  = NC_CLK_CK440_MXCK3_DP
  \mxck2#\  = CLK_100M_CK440_PCH_EXTCLK_R_DN
  MXCK2  = CLK_100M_CK440_PCH_EXTCLK_R_DP
  \mxck1#\  = NC_CLK_CK440_MXCK1_DN
  MXCK1  = NC_CLK_CK440_MXCK1_DP
  \mxck0#\  = NC_CLK_CK440_MXCK0_DN
  MXCK0  = NC_CLK_CK440_MXCK0_DP
  SBI_OUT  = TP_CK440_SBI_DATA_OUT
  SBI_CLK  = PD_CK440_SBI_CLK
  \25m2#\  = CLK_25M_CK440_ISCLK_REF_DN
  \25m2\  = CLK_25M_CK440_ISCLK_REF_DP
  VDDA25M  = P3V3_AUX_CLK_GEN_VDDA25M_CK440
  NC_B2  = NC_CK440_B2
  NC_B3  = NC_CK440_B3
  \pft_lost#\  = PU_CLK_PFT_LOST_N
  NC_B5  = NC_CK440_B5
  VDDPT  = P3V3_AUX_CLK_GEN_VDDPT_CK440
  NC_B7  = NC_CK440_B7
  SMBDATTA  = SMB_HOST_CLK_3V3AUX_SDA
  SMB_ADR1_TRI  = CLK_CK440_SMB_ADDR1
  GNDS  = GND
  XOUT  = XTAL_CLK_GEN1_25M_X2
  NVGND  = GND
  NC_B13  = NC_CK440_B13
  \oe6#\  = CK440Q_OE_6
  \oe5#\  = CK440Q_OE_5
  NC_B16  = NC_CK440_B16
  VDDA100M  = P3V3_AUX_CLK_GEN_VDDA100M_CK440
  NC_B18  = NC_CK440_B18
  \oe4#\  = CK440Q_OE_4
  NC_B20  = NC_CK440_B20
  VDD100M_B21  = P3V3_AUX_CLK_GEN_VDD_CK440
  NC_B22  = NC_CK440_B22
  VDD100M_B23  = P3V3_AUX_CLK_GEN_VDD_CK440
  NC_B24  = NC_CK440_B24
  NC_B25  = NC_CK440_B25
  NC_B26  = NC_CK440_B26
  \oe0#\  = FM_CLK_GEN1_OE0_N
  NC_B28  = NC_CK440_B28
  VDDMXCK_B29  = P3V3_AUX_CLK_GEN_VDDMXCK_CK440
  NC_B30  = NC_CK440_B30
  NC_B31  = NC_CK440_B31
  VDDMXCK_B32  = P3V3_AUX_CLK_GEN_VDDMXCK_CK440
  NC_B33  = NC_CK440_B33
  NC_B34  = NC_CK440_B34
  VDDMXCK_B35  = P3V3_AUX_CLK_GEN_VDDMXCK_CK440
  NC_B36  = NC_CK440_B36
  NC_B37  = NC_CK440_B37
  \mxck_sel_100m#\  = FM_CK440_MXCK_25M_100M
  NC_B39  = NC_CK440_B39
  VDDMXCK_B40  = P3V3_AUX_CLK_GEN_VDDMXCK_CK440
  NC_B41  = NC_CK440_B41
  \shft_ld#\  = PU_CK440_SHFT_LD_N
  SBI_IN  = PD_CK440_SBI_DATA_IN
  NC_B44  = NC_CK440_B44
  EPAD  = GND

(kicad_pcb
	(version 20260206)
	(generator "pcbnew")
	(generator_version "10.0")
	(general
		(thickness 1.6)
		(legacy_teardrops no)
	)
	(paper "A4")
	(title_block
		(title "03242023_DA0F0TMBIJ0_F0T_Motherboard_J_brd_V01_OCP.brd")
		(comment 1 "Grand Teton / footprint 1793 of 6105 (U13), pads 1-43 of 101")
	)
	(layers
		(0 "F.Cu" signal "TOP")
		(4 "In1.Cu" signal "GND")
		(6 "In2.Cu" signal "IN1")
		(8 "In3.Cu" signal "GND1")
		(10 "In4.Cu" signal "IN2")
		(12 "In5.Cu" signal "GND2")
		(14 "In6.Cu" signal "IN3")
		(16 "In7.Cu" signal "GND3")
		(18 "In8.Cu" signal "VCC")
		(20 "In9.Cu" signal "VCC1")
		(22 "In10.Cu" signal "GND4")
		(24 "In11.Cu" signal "IN4")
		(26 "In12.Cu" signal "GND5")
		(28 "In13.Cu" signal "IN5")
		(30 "In14.Cu" signal "GND6")
		(32 "In15.Cu" signal "IN6")
		(34 "In16.Cu" signal "GND7")
		(2 "B.Cu" signal "BOTTOM")
		(9 "F.Adhes" user "F.Adhesive")
		(11 "B.Adhes" user "B.Adhesive")
		(13 "F.Paste" user "Package Geometry/Pastemask Top")
		(15 "B.Paste" user "Package Geometry/Pastemask Bottom")
		(5 "F.SilkS" user "Ref Des/Silkscreen Top")
		(7 "B.SilkS" user "Ref Des/Silkscreen Bottom")
		(1 "F.Mask" user "Board Geometry/Soldermask Top")
		(3 "B.Mask" user "Board Geometry/Soldermask Bottom")
		(17 "Dwgs.User" user "User.Drawings")
		(19 "Cmts.User" user "User.Comments")
		(21 "Eco1.User" user "User.Eco1")
		(23 "Eco2.User" user "User.Eco2")
		(25 "Edge.Cuts" user "Board Geometry/Outline")
		(27 "Margin" user)
		(31 "F.CrtYd" user "Package Geometry/Place Bound Top")
		(29 "B.CrtYd" user "Package Geometry/Place Bound Bottom")
		(35 "F.Fab" user "Ref Des/Assembly Top")
		(33 "B.Fab" user "Ref Des/Assembly Bottom")
	)
	(footprint ""
		(layer "F.Cu")
		(at 255.68275 -99.563174)
		(property "Reference" "U13"
			(at 3.232404 -8.016748 0)
			(unlocked yes)
			(layer "F.SilkS")
			(effects
				(font
					(size 0.7874 0.5842)
					(thickness 0.1524)
				)
				(justify left)
			)
		)
		(property "Value" ""
			(at 0 0 0)
			(layer "F.Fab")
			(effects
				(font
					(size 1.27 1.27)
				)
			)
		)
		(duplicate_pad_numbers_are_jumpers no)
		(pad "A1" smd rect
			(at -3.875024 -3.24993 90)
			(size 0.1778 0.5588)
			(layers "F.Cu" "F.Mask" "F.Paste")
			(net "FM_CK440Q_DEV_25M_EN")
		)
		(pad "A2" smd rect
			(at -3.875024 -2.750058 90)
			(size 0.1778 0.5588)
			(layers "F.Cu" "F.Mask" "F.Paste")
			(net "CLK_25M_CK440_CPU1_DN")
		)
		(pad "A3" smd rect
			(at -3.875024 -2.249932 90)
			(size 0.1778 0.5588)
			(layers "F.Cu" "F.Mask" "F.Paste")
			(net "CLK_25M_CK440_CPU1_DP")
		)
		(pad "A4" smd rect
			(at -3.875024 -1.75006 90)
			(size 0.1778 0.5588)
			(layers "F.Cu" "F.Mask" "F.Paste")
			(net "CLK_25M_CK440_CPU0_DN")
		)
		(pad "A5" smd rect
			(at -3.875024 -1.249934 90)
			(size 0.1778 0.5588)
			(layers "F.Cu" "F.Mask" "F.Paste")
			(net "CLK_25M_CK440_CPU0_DP")
		)
		(pad "A6" smd rect
			(at -3.875024 -0.750062 90)
			(size 0.1778 0.5588)
			(layers "F.Cu" "F.Mask" "F.Paste")
			(net "TP_CLK_CK440_PFT_OUT_DP")
		)
		(pad "A7" smd rect
			(at -3.875024 -0.249936 90)
			(size 0.1778 0.5588)
			(layers "F.Cu" "F.Mask" "F.Paste")
			(net "TP_CLK_CK440_PFT_OUT_DN")
		)
		(pad "A8" smd rect
			(at -3.875024 0.249936 90)
			(size 0.1778 0.5588)
			(layers "F.Cu" "F.Mask" "F.Paste")
			(net "TP_CLK_PFT_IN_DP")
		)
		(pad "A9" smd rect
			(at -3.875024 0.750062 90)
			(size 0.1778 0.5588)
			(layers "F.Cu" "F.Mask" "F.Paste")
			(net "TP_CLK_PFT_IN_DN")
		)
		(pad "A10" smd rect
			(at -3.875024 1.249934 90)
			(size 0.1778 0.5588)
			(layers "F.Cu" "F.Mask" "F.Paste")
			(net "SMB_HOST_CLK_3V3AUX_SCL")
		)
		(pad "A11" smd rect
			(at -3.875024 1.75006 90)
			(size 0.1778 0.5588)
			(layers "F.Cu" "F.Mask" "F.Paste")
			(net "CLK_CK440_SMB_ADDR0")
		)
		(pad "A12" smd rect
			(at -3.875024 2.249932 90)
			(size 0.1778 0.5588)
			(layers "F.Cu" "F.Mask" "F.Paste")
			(net "P3V3_AUX_CLK_GEN_VDDXTAL_CK440")
		)
		(pad "A13" smd rect
			(at -3.875024 2.750058 90)
			(size 0.1778 0.5588)
			(layers "F.Cu" "F.Mask" "F.Paste")
			(net "XTAL_CLK_GEN1_25M_X1")
		)
		(pad "A14" smd rect
			(at -3.875024 3.24993 90)
			(size 0.1778 0.5588)
			(layers "F.Cu" "F.Mask" "F.Paste")
			(net "GND")
		)
		(pad "A15" smd rect
			(at -3.24993 3.875024)
			(size 0.1778 0.5588)
			(layers "F.Cu" "F.Mask" "F.Paste")
			(net "NC_CK440_A15")
		)
		(pad "A16" smd rect
			(at -2.750058 3.875024)
			(size 0.1778 0.5588)
			(layers "F.Cu" "F.Mask" "F.Paste")
			(net "FM_CLK_CK440_SS_EN")
		)
		(pad "A17" smd rect
			(at -2.249932 3.875024)
			(size 0.1778 0.5588)
			(layers "F.Cu" "F.Mask" "F.Paste")
			(net "FM_PLD_CLKS_DEV_EN")
		)
		(pad "A18" smd rect
			(at -1.75006 3.875024)
			(size 0.1778 0.5588)
			(layers "F.Cu" "F.Mask" "F.Paste")
			(net "NC_CLK_CK440_100M6_DN")
		)
		(pad "A19" smd rect
			(at -1.249934 3.875024)
			(size 0.1778 0.5588)
			(layers "F.Cu" "F.Mask" "F.Paste")
			(net "NC_CLK_CK440_100M6_DP")
		)
		(pad "A20" smd rect
			(at -0.750062 3.875024)
			(size 0.1778 0.5588)
			(layers "F.Cu" "F.Mask" "F.Paste")
			(net "NC_CLK_CK440_100M5_DN")
		)
		(pad "A21" smd rect
			(at -0.249936 3.875024)
			(size 0.1778 0.5588)
			(layers "F.Cu" "F.Mask" "F.Paste")
			(net "NC_CLK_CK440_100M5_DP")
		)
		(pad "A22" smd rect
			(at 0.249936 3.875024)
			(size 0.1778 0.5588)
			(layers "F.Cu" "F.Mask" "F.Paste")
			(net "NC_CLK_CK440_100M4_DN")
		)
		(pad "A23" smd rect
			(at 0.750062 3.875024)
			(size 0.1778 0.5588)
			(layers "F.Cu" "F.Mask" "F.Paste")
			(net "NC_CLK_CK440_100M4_DP")
		)
		(pad "A24" smd rect
			(at 1.249934 3.875024)
			(size 0.1778 0.5588)
			(layers "F.Cu" "F.Mask" "F.Paste")
			(net "NC_CLK_CK440_100M3_DN")
		)
		(pad "A25" smd rect
			(at 1.75006 3.875024)
			(size 0.1778 0.5588)
			(layers "F.Cu" "F.Mask" "F.Paste")
			(net "NC_CLK_CK440_100M3_DP")
		)
		(pad "A26" smd rect
			(at 2.249932 3.875024)
			(size 0.1778 0.5588)
			(layers "F.Cu" "F.Mask" "F.Paste")
			(net "CK440Q_OE_3")
		)
		(pad "A27" smd rect
			(at 2.750058 3.875024)
			(size 0.1778 0.5588)
			(layers "F.Cu" "F.Mask" "F.Paste")
			(net "NC_CLK_CK440_100M2_DN")
		)
		(pad "A28" smd rect
			(at 3.24993 3.875024)
			(size 0.1778 0.5588)
			(layers "F.Cu" "F.Mask" "F.Paste")
			(net "NC_CLK_CK440_100M2_DP")
		)
		(pad "A29" smd rect
			(at 3.875024 3.24993 270)
			(size 0.1778 0.5588)
			(layers "F.Cu" "F.Mask" "F.Paste")
			(net "CK440Q_OE_2")
		)
		(pad "A30" smd rect
			(at 3.875024 2.750058 270)
			(size 0.1778 0.5588)
			(layers "F.Cu" "F.Mask" "F.Paste")
			(net "CK440Q_OE_1")
		)
		(pad "A31" smd rect
			(at 3.875024 2.249932 270)
			(size 0.1778 0.5588)
			(layers "F.Cu" "F.Mask" "F.Paste")
			(net "NC_CLK_CK440_100M1_DN")
		)
		(pad "A32" smd rect
			(at 3.875024 1.75006 270)
			(size 0.1778 0.5588)
			(layers "F.Cu" "F.Mask" "F.Paste")
			(net "NC_CLK_CK440_100M1_DP")
		)
		(pad "A33" smd rect
			(at 3.875024 1.249934 270)
			(size 0.1778 0.5588)
			(layers "F.Cu" "F.Mask" "F.Paste")
			(net "CLK_100M_DB2000_DN")
		)
		(pad "A34" smd rect
			(at 3.875024 0.750062 270)
			(size 0.1778 0.5588)
			(layers "F.Cu" "F.Mask" "F.Paste")
			(net "CLK_100M_DB2000_DP")
		)
		(pad "A35" smd rect
			(at 3.875024 0.249936 270)
			(size 0.1778 0.5588)
			(layers "F.Cu" "F.Mask" "F.Paste")
			(net "NC_CLK_CK440_MXCK8_DN")
		)
		(pad "A36" smd rect
			(at 3.875024 -0.249936 270)
			(size 0.1778 0.5588)
			(layers "F.Cu" "F.Mask" "F.Paste")
			(net "NC_CLK_CK440_MXCK8_DP")
		)
		(pad "A37" smd rect
			(at 3.875024 -0.750062 270)
			(size 0.1778 0.5588)
			(layers "F.Cu" "F.Mask" "F.Paste")
			(net "NC_CLK_CK440_MXCK7_DN")
		)
		(pad "A38" smd rect
			(at 3.875024 -1.249934 270)
			(size 0.1778 0.5588)
			(layers "F.Cu" "F.Mask" "F.Paste")
			(net "NC_CLK_CK440_MXCK7_DP")
		)
		(pad "A39" smd rect
			(at 3.875024 -1.75006 270)
			(size 0.1778 0.5588)
			(layers "F.Cu" "F.Mask" "F.Paste")
			(net "NC_CLK_CK440_MXCK6_DN")
		)
		(pad "A40" smd rect
			(at 3.875024 -2.249932 270)
			(size 0.1778 0.5588)
			(layers "F.Cu" "F.Mask" "F.Paste")
			(net "NC_CLK_CK440_MXCK6_DP")
		)
		(pad "A41" smd rect
			(at 3.875024 -2.750058 270)
			(size 0.1778 0.5588)
			(layers "F.Cu" "F.Mask" "F.Paste")
			(net "NC_CLK_CK440_MXCK5_DN")
		)
		(pad "A42" smd rect
			(at 3.875024 -3.24993 270)
			(size 0.1778 0.5588)
			(layers "F.Cu" "F.Mask" "F.Paste")
			(net "NC_CLK_CK440_MXCK5_DP")
		)
		(pad "A43" smd rect
			(at 3.24993 -3.875024)
			(size 0.1778 0.5588)
			(layers "F.Cu" "F.Mask" "F.Paste")
			(net "NC_CLK_CK440_MXCK4_DN")
		)
	)
)
